FILE_TYPE = CONNECTIVITY;
{Allegro Design Entry HDL 17.2-2016 S081 (4005846) 1/11/2022}
"PAGE_NUMBER" = 33;
0"NC";
1"GND\g";
2"GND\g";
%"GENOA_SP5"
"40","(-4750,3750)","1","pure_quanta","I4";
;
LOCATION"U25"
$SEC"40"
CDS_SEC"40"
PART_TYPE"SMLF"
MATERIAL"IO"
VALUE"SOCKET6096_13568-001"
PART_NUMBER"DGA^6000030"
CDS_LMAN_SYM_OUTLINE"-400,3350,400,-3350"
CDS_LIB"pure_quanta"
NEEDS_NO_SIZE"TRUE";
"VSS_V68"
$PN"V68"2;
"VSS_BV42"
$PN"BV42"2;
"VSS_CT52"
$PN"CT52"2;
"VSS_CM50"
$PN"CM50"2;
"VSS_K59"
$PN"K59"2;
"VSS_DA56"
$PN"DA56"2;
"VSS_CG42"
$PN"CG42"2;
"VSS_AE4"
$PN"AE4"2;
"VSS_AH33"
$PN"AH33"2;
"VSS_BW25"
$PN"BW25"2;
"VSS_CU58"
$PN"CU58"2;
"VSS_P25"
$PN"P25"2;
"VSS_P68"
$PN"P68"2;
"VSS_AN20"
$PN"AN20"2;
"VSS_CC22"
$PN"CC22"2;
"VSS_CF46"
$PN"CF46"2;
"VSS_V27"
$PN"V27"2;
"VSS_AA42"
$PN"AA42"2;
"VSS_AD31"
$PN"AD31"2;
"VSS_AJ13"
$PN"AJ13"2;
"VSS_AA72"
$PN"AA72"2;
"VSS_CK10"
$PN"CK10"2;
"VSS_CN54"
$PN"CN54"2;
"VSS_K23"
$PN"K23"2;
"VSS_AM37"
$PN"AM37"2;
"VSS_CB44"
$PN"CB44"2;
"VSS_CK31"
$PN"CK31"2;
"VSS_CY57"
$PN"CY57"2;
"VSS_DJ73"
$PN"DJ73"2;
"VSS_DJ68"
$PN"DJ68"2;
"VSS_DJ66"
$PN"DJ66"2;
"VSS_DJ63"
$PN"DJ63"2;
"VSS_DJ61"
$PN"DJ61"2;
"VSS_DJ59"
$PN"DJ59"2;
"VSS_DJ49"
$PN"DJ49"2;
"VSS_DJ43"
$PN"DJ43"2;
"VSS_DJ19"
$PN"DJ19"2;
"VSS_DJ15"
$PN"DJ15"2;
"VSS_DJ7"
$PN"DJ7"2;
"VSS_DH70"
$PN"DH70"2;
"VSS_DH68"
$PN"DH68"2;
"VSS_DH59"
$PN"DH59"2;
"VSS_DH55"
$PN"DH55"2;
"VSS_DH52"
$PN"DH52"2;
"VSS_DH49"
$PN"DH49"2;
"VSS_DH46"
$PN"DH46"2;
"VSS_DH43"
$PN"DH43"2;
"VSS_DH39"
$PN"DH39"2;
"VSS_DG75"
$PN"DG75"2;
"VSS_DG74"
$PN"DG74"2;
"VSS_DG70"
$PN"DG70"2;
"VSS_DG69"
$PN"DG69"2;
"VSS_DG68"
$PN"DG68"2;
"VSS_DG67"
$PN"DG67"2;
"VSS_DG66"
$PN"DG66"2;
"VSS_DG60"
$PN"DG60"2;
"VSS_DG59"
$PN"DG59"2;
"VSS_DG56"
$PN"DG56"2;
"VSS_DG55"
$PN"DG55"2;
"VSS_DG52"
$PN"DG52"2;
"VSS_DG49"
$PN"DG49"2;
"VSS_DG46"
$PN"DG46"2;
"VSS_DG27"
$PN"DG27"2;
"VSS_DG24"
$PN"DG24"2;
"VSS_DG21"
$PN"DG21"2;
"VSS_DG20"
$PN"DG20"2;
"VSS_DG18"
$PN"DG18"2;
"VSS_DG16"
$PN"DG16"2;
"VSS_DG15"
$PN"DG15"2;
"VSS_DG7"
$PN"DG7"2;
"VSS_DG6"
$PN"DG6"2;
"VSS_DG2"
$PN"DG2"2;
"VSS_DG1"
$PN"DG1"2;
"VSS_DF73"
$PN"DF73"2;
"VSS_DF72"
$PN"DF72"2;
"VSS_DF71"
$PN"DF71"2;
"VSS_DF65"
$PN"DF65"2;
"VSS_DF64"
$PN"DF64"2;
"VSS_DF63"
$PN"DF63"2;
"VSS_DF61"
$PN"DF61"2;
"VSS_DF59"
$PN"DF59"2;
"VSS_DF58"
$PN"DF58"2;
"VSS_DF57"
$PN"DF57"2;
"VSS_DF56"
$PN"DF56"2;
"VSS_DF52"
$PN"DF52"2;
"VSS_DF51"
$PN"DF51"2;
"VSS_DF50"
$PN"DF50"2;
"VSS_DF49"
$PN"DF49"2;
"VSS_DF48"
$PN"DF48"2;
"VSS_DF47"
$PN"DF47"2;
"VSS_DF46"
$PN"DF46"2;
"VSS_DF45"
$PN"DF45"2;
"VSS_DF44"
$PN"DF44"2;
"VSS_DF42"
$PN"DF42"2;
"VSS_DF39"
$PN"DF39"2;
"VSS_DF37"
$PN"DF37"2;
"VSS_DF35"
$PN"DF35"2;
"VSS_DF32"
$PN"DF32"2;
"VSS_DF29"
$PN"DF29"2;
"VSS_DF26"
$PN"DF26"2;
"VSS_DF23"
$PN"DF23"2;
"VSS_DF22"
$PN"DF22"2;
"VSS_DF20"
$PN"DF20"2;
"VSS_DF13"
$PN"DF13"1;
"VSS_DF12"
$PN"DF12"1;
"VSS_DF11"
$PN"DF11"1;
"VSS_DF10"
$PN"DF10"1;
"VSS_DF8"
$PN"DF8"1;
"VSS_DF6"
$PN"DF6"1;
"VSS_DF5"
$PN"DF5"1;
"VSS_DE68"
$PN"DE68"1;
"VSS_DE63"
$PN"DE63"1;
"VSS_DE61"
$PN"DE61"1;
"VSS_DE56"
$PN"DE56"1;
"VSS_DE33"
$PN"DE33"1;
"VSS_DE29"
$PN"DE29"1;
"VSS_DE26"
$PN"DE26"1;
"VSS_DE8"
$PN"DE8"1;
"VSS_DE6"
$PN"DE6"1;
"VSS_DE1"
$PN"DE1"1;
"VSS_DD73"
$PN"DD73"1;
"VSS_DD71"
$PN"DD71"1;
"VSS_DD68"
$PN"DD68"1;
"VSS_DD66"
$PN"DD66"1;
"VSS_DD53"
$PN"DD53"1;
"VSS_DD52"
$PN"DD52"1;
"VSS_DD50"
$PN"DD50"1;
"VSS_DD49"
$PN"DD49"1;
"VSS_DD47"
$PN"DD47"1;
"VSS_DD46"
$PN"DD46"1;
"VSS_DD44"
$PN"DD44"1;
"VSS_DD37"
$PN"DD37"1;
"VSS_DD36"
$PN"DD36"1;
"VSS_DD35"
$PN"DD35"1;
"VSS_DD33"
$PN"DD33"1;
"VSS_DD32"
$PN"DD32"1;
"VSS_DD30"
$PN"DD30"1;
"VSS_DD29"
$PN"DD29"1;
"VSS_DD19"
$PN"DD19"1;
"VSS_DD17"
$PN"DD17"1;
"VSS_DD15"
$PN"DD15"1;
"VSS_DD12"
$PN"DD12"1;
"VSS_DD10"
$PN"DD10"1;
"VSS_DD8"
$PN"DD8"1;
"VSS_DD5"
$PN"DD5"1;
"VSS_DC68"
$PN"DC68"1;
"VSS_DC65"
$PN"DC65"1;
"VSS_DC63"
$PN"DC63"1;
"VSS_DC61"
$PN"DC61"1;
"VSS_DC58"
$PN"DC58"1;
"VSS_DC56"
$PN"DC56"1;
"VSS_DC54"
$PN"DC54"1;
"VSS_DC42"
$PN"DC42"1;
"VSS_DC34"
$PN"DC34"1;
"VSS_DC31"
$PN"DC31"1;
"VSS_DC28"
$PN"DC28"1;
"VSS_DC25"
$PN"DC25"1;
"VSS_DC22"
$PN"DC22"1;
"VSS_DC20"
$PN"DC20"1;
"VSS_DC18"
$PN"DC18"1;
"VSS_DC11"
$PN"DC11"1;
"VSS_DC8"
$PN"DC8"1;
"VSS_DC6"
$PN"DC6"1;
"VSS_DC4"
$PN"DC4"1;
"VSS_DC1"
$PN"DC1"1;
"VSS_DB73"
$PN"DB73"1;
"VSS_DB68"
$PN"DB68"1;
"VSS_DB66"
$PN"DB66"1;
"VSS_DB61"
$PN"DB61"1;
"VSS_DB45"
$PN"DB45"1;
"VSS_DB42"
$PN"DB42"1;
"VSS_DB39"
$PN"DB39"1;
"VSS_DB37"
$PN"DB37"1;
"VSS_DB34"
$PN"DB34"1;
"VSS_DB31"
$PN"DB31"1;
"VSS_DB28"
$PN"DB28"1;
"VSS_DB10"
$PN"DB10"1;
"VSS_DB8"
$PN"DB8"1;
"VSS_DB3"
$PN"DB3"1;
"VSS_DA75"
$PN"DA75"1;
"VSS_DA72"
$PN"DA72"1;
"VSS_DH66"
$PN"DH66"2;
"VSS_DH64"
$PN"DH64"2;
"VSS_DH63"
$PN"DH63"2;
"VSS_DH61"
$PN"DH61"2;
"VSS_DH37"
$PN"DH37"2;
"VSS_DH18"
$PN"DH18"2;
"VSS_DH11"
$PN"DH11"2;
"VSS_DH5"
$PN"DH5"2;
"VSS_DG65"
$PN"DG65"2;
"VSS_DG63"
$PN"DG63"2;
"VSS_DG62"
$PN"DG62"2;
"VSS_DG61"
$PN"DG61"2;
"VSS_DG43"
$PN"DG43"2;
"VSS_DG41"
$PN"DG41"2;
"VSS_DG33"
$PN"DG33"2;
"VSS_DG30"
$PN"DG30"2;
"VSS_DG14"
$PN"DG14"2;
"VSS_DG13"
$PN"DG13"2;
"VSS_DG9"
$PN"DG9"2;
"VSS_DG8"
$PN"DG8"2;
"VSS_DF70"
$PN"DF70"2;
"VSS_DF68"
$PN"DF68"2;
"VSS_DF66"
$PN"DF66"2;
"VSS_DF54"
$PN"DF54"2;
"VSS_DF53"
$PN"DF53"2;
"VSS_DF43"
$PN"DF43"2;
"VSS_DF19"
$PN"DF19"1;
"VSS_DF18"
$PN"DF18"1;
"VSS_DF17"
$PN"DF17"1;
"VSS_DF15"
$PN"DF15"1;
"VSS_DF4"
$PN"DF4"1;
"VSS_DF3"
$PN"DF3"1;
"VSS_DE75"
$PN"DE75"1;
"VSS_DE70"
$PN"DE70"1;
"VSS_DE23"
$PN"DE23"1;
"VSS_DE20"
$PN"DE20"1;
"VSS_DE15"
$PN"DE15"1;
"VSS_DE13"
$PN"DE13"1;
"VSS_DD64"
$PN"DD64"1;
"VSS_DD61"
$PN"DD61"1;
"VSS_DD59"
$PN"DD59"1;
"VSS_DD57"
$PN"DD57"1;
"VSS_DD43"
$PN"DD43"1;
"VSS_DD41"
$PN"DD41"1;
"VSS_DD40"
$PN"DD40"1;
"VSS_DD39"
$PN"DD39"1;
"VSS_DD27"
$PN"DD27"1;
"VSS_DD26"
$PN"DD26"1;
"VSS_DD24"
$PN"DD24"1;
"VSS_DD23"
$PN"DD23"1;
"VSS_DD3"
$PN"DD3"1;
"VSS_DC75"
$PN"DC75"1;
"VSS_DC72"
$PN"DC72"1;
"VSS_DC70"
$PN"DC70"1;
"VSS_DC51"
$PN"DC51"1;
"VSS_DC48"
$PN"DC48"1;
"VSS_DC45"
$PN"DC45"1;
"VSS_DC15"
$PN"DC15"1;
"VSS_DC13"
$PN"DC13"1;
"VSS_DB59"
$PN"DB59"1;
"VSS_DB54"
$PN"DB54"1;
"VSS_DB51"
$PN"DB51"1;
"VSS_DB48"
$PN"DB48"1;
"VSS_DB25"
$PN"DB25"1;
"VSS_DB22"
$PN"DB22"1;
"VSS_DB17"
$PN"DB17"1;
"VSS_DB15"
$PN"DB15"1;
%"UNIVERSAL_GND"
"1","(-1300,4475)","1","pure_quanta_power","I5";
;
CDS_LIB"pure_quanta_power"
HDL_POWER"GND";
"A"2;
%"UNIVERSAL_GND"
"1","(-1875,3025)","1","pure_quanta_power","I6";
;
CDS_LIB"pure_quanta_power"
HDL_POWER"GND";
"A"1;
END.
